# Thunderbolt PCIe Adaper — symbol library table
(sym_lib_table
  (version 7)
)
